(kicad_pcb
	(version 20260206)
	(generator "pcbnew")
	(generator_version "10.0")
	(general
		(thickness 1.6)
		(legacy_teardrops no)
	)
	(paper "A4")
	(title_block
		(title "timecard-production-celestica-r4006 — R4006-B0001-02_R01.brd")
		(comment 1 "Time Appliance Project (Time Card) / footprints 340-346 of 1113")
	)
	(layers
		(0 "F.Cu" signal "TOP")
		(4 "In1.Cu" signal "L02_GND1")
		(6 "In2.Cu" signal "L03_SIG1")
		(8 "In3.Cu" signal "L04_GND2")
		(10 "In4.Cu" signal "L05_VCC1")
		(12 "In5.Cu" signal "L06_VCC2")
		(14 "In6.Cu" signal "L07_GND3")
		(16 "In7.Cu" signal "L08_SIG2")
		(18 "In8.Cu" signal "L09_GND4")
		(2 "B.Cu" signal "BOTTOM")
		(9 "F.Adhes" user "F.Adhesive")
		(11 "B.Adhes" user "B.Adhesive")
		(13 "F.Paste" user "Package Geometry/Pastemask Top")
		(15 "B.Paste" user "Package Geometry/Pastemask Bottom")
		(5 "F.SilkS" user "Ref Des/Silkscreen Top")
		(7 "B.SilkS" user "Ref Des/Silkscreen Bottom")
		(1 "F.Mask" user "Board Geometry/Soldermask Top")
		(3 "B.Mask" user "Board Geometry/Soldermask Bottom")
		(17 "Dwgs.User" user "User.Drawings")
		(19 "Cmts.User" user "User.Comments")
		(21 "Eco1.User" user "User.Eco1")
		(23 "Eco2.User" user "User.Eco2")
		(25 "Edge.Cuts" user "Board Geometry/Outline")
		(27 "Margin" user)
		(31 "F.CrtYd" user "Package Geometry/Place Bound Top")
		(29 "B.CrtYd" user "Package Geometry/Place Bound Bottom")
		(35 "F.Fab" user "Ref Des/Assembly Top")
		(33 "B.Fab" user "Ref Des/Assembly Bottom")
	)
	(footprint ""
		(layer "F.Cu")
		(at 36.9824 -101.3714 180)
		(property "Reference" "C31"
			(at 4.064 1.73863 0)
			(unlocked yes)
			(layer "F.SilkS")
			(effects
				(font
					(size 0.7874 0.5842)
					(thickness 0.1524)
				)
			)
		)
		(property "Value" "VAL*"
			(at 0.0762 2.067306 180)
			(unlocked yes)
			(layer "F.Fab")
			(hide yes)
			(effects
				(font
					(size 0.7874 0.5842)
					(thickness 0.1524)
				)
			)
		)
		(property "Device Type" "CAPACITOR-G105-0B223-EK,0.022UA"
			(at 0.0508 1.127506 180)
			(unlocked yes)
			(layer "F.Fab")
			(hide yes)
			(effects
				(font
					(size 0.7874 0.5842)
					(thickness 0.1524)
				)
			)
		)
		(property "User Part Number" "PARTNUM*"
			(at 0.1016 4.023106 180)
			(unlocked yes)
			(layer "Cmts.User")
			(hide yes)
			(effects
				(font
					(size 0.7874 0.5842)
					(thickness 0.1524)
				)
			)
		)
		(property "Tolerance" "TOL*"
			(at 0.0762 3.032506 180)
			(unlocked yes)
			(layer "Cmts.User")
			(hide yes)
			(effects
				(font
					(size 0.7874 0.5842)
					(thickness 0.1524)
				)
			)
		)
		(duplicate_pad_numbers_are_jumpers no)
		(fp_line
			(start 1.143 0.5588)
			(end 1.143 -0.5588)
			(stroke
				(width 0.1)
				(type default)
			)
			(layer "F.SilkS")
		)
		(fp_line
			(start 1.143 -0.5588)
			(end -1.143 -0.5588)
			(stroke
				(width 0.1)
				(type default)
			)
			(layer "F.SilkS")
		)
		(fp_line
			(start -1.143 0.5588)
			(end 1.143 0.5588)
			(stroke
				(width 0.1)
				(type default)
			)
			(layer "F.SilkS")
		)
		(fp_line
			(start -1.143 -0.5588)
			(end -1.143 0.5588)
			(stroke
				(width 0.1)
				(type default)
			)
			(layer "F.SilkS")
		)
		(fp_rect
			(start -1.143 0.5588)
			(end 1.143 -0.5588)
			(stroke
				(width 0)
				(type default)
			)
			(fill no)
			(layer "F.CrtYd")
		)
		(fp_line
			(start 0.508 0.3048)
			(end 0.508 -0.3048)
			(stroke
				(width 0.1)
				(type default)
			)
			(layer "F.Fab")
		)
		(fp_line
			(start 0.508 -0.3048)
			(end -0.508 -0.3048)
			(stroke
				(width 0.1)
				(type default)
			)
			(layer "F.Fab")
		)
		(fp_line
			(start -0.508 0.3048)
			(end 0.508 0.3048)
			(stroke
				(width 0.1)
				(type default)
			)
			(layer "F.Fab")
		)
		(fp_line
			(start -0.508 -0.3048)
			(end -0.508 0.3048)
			(stroke
				(width 0.1)
				(type default)
			)
			(layer "F.Fab")
		)
		(pad "1" smd rect
			(at -0.5334 0 180)
			(size 0.7112 0.6096)
			(layers "F.Cu" "F.Mask" "F.Paste")
			(net "XP5R0V_SS")
		)
		(pad "2" smd rect
			(at 0.5334 0 180)
			(size 0.7112 0.6096)
			(layers "F.Cu" "F.Mask" "F.Paste")
			(net "XP5R0V_AGND")
		)
		(zone
			(layer "F.Cu")
			(hatch none 0.5)
			(connect_pads
				(clearance 0)
			)
			(min_thickness 0.25)
			(keepout
				(tracks allowed)
				(vias not_allowed)
				(pads allowed)
				(copperpour not_allowed)
				(footprints allowed)
			)
			(placement
				(enabled no)
				(sheetname "")
			)
			(fill
				(thermal_gap 0.5)
				(thermal_bridge_width 0.5)
				(island_removal_mode 0)
			)
			(polygon
				(pts
					(xy 37.0586 -101.6762) (xy 36.9062 -101.6762) (xy 36.9062 -101.0666) (xy 37.0586 -101.0666)
				)
			)
		)
	)
	(footprint ""
		(layer "F.Cu")
		(at 89.9922 -97.3582 180)
		(property "Reference" "R40"
			(at -1.778 -2.45237 0)
			(unlocked yes)
			(layer "F.SilkS")
			(effects
				(font
					(size 0.7874 0.5842)
					(thickness 0.1524)
				)
			)
		)
		(property "Value" "VAL*"
			(at 0.02032 2.13233 180)
			(unlocked yes)
			(layer "F.Fab")
			(hide yes)
			(effects
				(font
					(size 0.7874 0.5842)
					(thickness 0.1524)
				)
			)
		)
		(property "Tolerance" "TOL*"
			(at 0.044704 3.05435 180)
			(unlocked yes)
			(layer "Cmts.User")
			(hide yes)
			(effects
				(font
					(size 0.7874 0.5842)
					(thickness 0.1524)
				)
			)
		)
		(property "User Part Number" "PARTNUM*"
			(at 0.02032 4.024884 180)
			(unlocked yes)
			(layer "Cmts.User")
			(hide yes)
			(effects
				(font
					(size 0.7874 0.5842)
					(thickness 0.1524)
				)
			)
		)
		(property "Device Type" "RESISTOR-G155-12002-01,20KOHM,A"
			(at 0.008382 1.210564 180)
			(unlocked yes)
			(layer "F.Fab")
			(hide yes)
			(effects
				(font
					(size 0.7874 0.5842)
					(thickness 0.1524)
				)
			)
		)
		(duplicate_pad_numbers_are_jumpers no)
		(fp_line
			(start 1.143 0.5588)
			(end 1.143 -0.5588)
			(stroke
				(width 0.1)
				(type default)
			)
			(layer "F.SilkS")
		)
		(fp_line
			(start 1.143 -0.5588)
			(end -1.143 -0.5588)
			(stroke
				(width 0.1)
				(type default)
			)
			(layer "F.SilkS")
		)
		(fp_line
			(start -1.143 0.5588)
			(end 1.143 0.5588)
			(stroke
				(width 0.1)
				(type default)
			)
			(layer "F.SilkS")
		)
		(fp_line
			(start -1.143 -0.5588)
			(end -1.143 0.5588)
			(stroke
				(width 0.1)
				(type default)
			)
			(layer "F.SilkS")
		)
		(fp_rect
			(start 1.143 -0.5588)
			(end -1.143 0.5588)
			(stroke
				(width 0)
				(type default)
			)
			(fill no)
			(layer "F.CrtYd")
		)
		(fp_line
			(start 0.508 0.3048)
			(end 0.508 -0.3048)
			(stroke
				(width 0.1)
				(type default)
			)
			(layer "F.Fab")
		)
		(fp_line
			(start 0.508 -0.3048)
			(end -0.508 -0.3048)
			(stroke
				(width 0.1)
				(type default)
			)
			(layer "F.Fab")
		)
		(fp_line
			(start -0.508 0.3048)
			(end 0.508 0.3048)
			(stroke
				(width 0.1)
				(type default)
			)
			(layer "F.Fab")
		)
		(fp_line
			(start -0.508 -0.3048)
			(end -0.508 0.3048)
			(stroke
				(width 0.1)
				(type default)
			)
			(layer "F.Fab")
		)
		(pad "1" smd rect
			(at -0.5334 0 180)
			(size 0.7112 0.6096)
			(layers "F.Cu" "F.Mask" "F.Paste")
			(net "UNNAMED_517_CAPACITOR_I30_1")
		)
		(pad "2" smd rect
			(at 0.5334 0 180)
			(size 0.7112 0.6096)
			(layers "F.Cu" "F.Mask" "F.Paste")
			(net "XP3R3V_FB_R_TO_AGND")
		)
		(zone
			(layer "F.Cu")
			(hatch none 0.5)
			(connect_pads
				(clearance 0)
			)
			(min_thickness 0.25)
			(keepout
				(tracks allowed)
				(vias not_allowed)
				(pads allowed)
				(copperpour not_allowed)
				(footprints allowed)
			)
			(placement
				(enabled no)
				(sheetname "")
			)
			(fill
				(thermal_gap 0.5)
				(thermal_bridge_width 0.5)
				(island_removal_mode 0)
			)
			(polygon
				(pts
					(xy 89.916 -97.0534) (xy 90.0684 -97.0534) (xy 90.0684 -97.663) (xy 89.916 -97.663)
				)
			)
		)
	)
	(footprint ""
		(layer "F.Cu")
		(at 32.512 -96.266 180)
		(property "Reference" "C86"
			(at -2.70637 -1.016 90)
			(unlocked yes)
			(layer "F.SilkS")
			(effects
				(font
					(size 0.7874 0.5842)
					(thickness 0.1524)
				)
			)
		)
		(property "Value" "VAL*"
			(at 0.193548 2.13614 180)
			(unlocked yes)
			(layer "F.Fab")
			(hide yes)
			(effects
				(font
					(size 0.7874 0.5842)
					(thickness 0.1524)
				)
			)
		)
		(property "Tolerance" "TOL*"
			(at 0.216154 3.1496 180)
			(unlocked yes)
			(layer "Cmts.User")
			(hide yes)
			(effects
				(font
					(size 0.7874 0.5842)
					(thickness 0.1524)
				)
			)
		)
		(property "Device Type" "CAPACITOR-G104-0A180-FJ,18PF,5%"
			(at 0.184404 1.180592 180)
			(unlocked yes)
			(layer "F.Fab")
			(hide yes)
			(effects
				(font
					(size 0.7874 0.5842)
					(thickness 0.1524)
				)
			)
		)
		(property "User Part Number" "PARTNUM*"
			(at 0.216154 4.185666 180)
			(unlocked yes)
			(layer "Cmts.User")
			(hide yes)
			(effects
				(font
					(size 0.7874 0.5842)
					(thickness 0.1524)
				)
			)
		)
		(duplicate_pad_numbers_are_jumpers no)
		(fp_line
			(start 0.671322 0.4445)
			(end -0.671322 0.4445)
			(stroke
				(width 0.1)
				(type default)
			)
			(layer "F.SilkS")
		)
		(fp_line
			(start 0.671322 -0.4445)
			(end 0.671322 0.4445)
			(stroke
				(width 0.1)
				(type default)
			)
			(layer "F.SilkS")
		)
		(fp_line
			(start -0.671322 0.4445)
			(end -0.671322 -0.4445)
			(stroke
				(width 0.1)
				(type default)
			)
			(layer "F.SilkS")
		)
		(fp_line
			(start -0.671322 -0.4445)
			(end 0.671322 -0.4445)
			(stroke
				(width 0.1)
				(type default)
			)
			(layer "F.SilkS")
		)
		(fp_rect
			(start 0.671322 0.4445)
			(end -0.671322 -0.4445)
			(stroke
				(width 0)
				(type default)
			)
			(fill no)
			(layer "F.CrtYd")
		)
		(fp_line
			(start 0.31496 0.1651)
			(end 0.31496 -0.1651)
			(stroke
				(width 0.1)
				(type default)
			)
			(layer "F.Fab")
		)
		(fp_line
			(start 0.31496 -0.1651)
			(end -0.31496 -0.1651)
			(stroke
				(width 0.1)
				(type default)
			)
			(layer "F.Fab")
		)
		(fp_line
			(start -0.31496 0.1651)
			(end 0.31496 0.1651)
			(stroke
				(width 0.1)
				(type default)
			)
			(layer "F.Fab")
		)
		(fp_line
			(start -0.31496 -0.1651)
			(end -0.31496 0.1651)
			(stroke
				(width 0.1)
				(type default)
			)
			(layer "F.Fab")
		)
		(pad "1" smd rect
			(at -0.264922 0 180)
			(size 0.3048 0.381)
			(layers "F.Cu" "F.Mask" "F.Paste")
			(net "SG")
		)
		(pad "2" smd rect
			(at 0.264922 0 180)
			(size 0.3048 0.381)
			(layers "F.Cu" "F.Mask" "F.Paste")
			(net "UNNAMED_524_CAPACITOR_I7_2")
		)
		(zone
			(layer "F.Cu")
			(hatch none 0.5)
			(connect_pads
				(clearance 0)
			)
			(min_thickness 0.25)
			(keepout
				(tracks allowed)
				(vias not_allowed)
				(pads allowed)
				(copperpour not_allowed)
				(footprints allowed)
			)
			(placement
				(enabled no)
				(sheetname "")
			)
			(fill
				(thermal_gap 0.5)
				(thermal_bridge_width 0.5)
				(island_removal_mode 0)
			)
			(polygon
				(pts
					(xy 32.399478 -96.4565) (xy 32.399478 -96.0755) (xy 32.624522 -96.0755) (xy 32.624522 -96.4565)
				)
			)
		)
	)
	(footprint ""
		(layer "F.Cu")
		(at 69.469 -129.794)
		(property "Reference" "SP48"
			(at 0 0 0)
			(layer "F.SilkS")
			(hide yes)
			(effects
				(font
					(size 1.27 1.27)
				)
			)
		)
		(property "Value" ""
			(at 0 0 0)
			(layer "F.Fab")
			(effects
				(font
					(size 1.27 1.27)
				)
			)
		)
		(duplicate_pad_numbers_are_jumpers no)
	)
	(footprint ""
		(layer "F.Cu")
		(at 122.682 -33.782 90)
		(property "Reference" "TP199"
			(at -1.0668 1.42875 90)
			(unlocked yes)
			(layer "F.SilkS")
			(effects
				(font
					(size 0.635 0.4064)
					(thickness 0.1524)
				)
				(justify left)
			)
		)
		(property "Value" ""
			(at 0 0 90)
			(layer "F.Fab")
			(effects
				(font
					(size 1.27 1.27)
				)
			)
		)
		(property "Device Type" "TP_PIONT-TP010CT020B030_PTH-TPA"
			(at -1.341882 0.996696 90)
			(unlocked yes)
			(layer "F.Fab")
			(hide yes)
			(effects
				(font
					(size 0.7874 0.5842)
					(thickness 0.1524)
				)
				(justify left)
			)
		)
		(duplicate_pad_numbers_are_jumpers no)
		(fp_poly
			(pts
				(arc
					(start 0 0.889)
					(mid 0 -0.889)
					(end 0 0.889)
				)
			)
			(stroke
				(width 0)
				(type default)
			)
			(fill no)
			(layer "B.CrtYd")
		)
		(fp_poly
			(pts
				(arc
					(start 0 0.889)
					(mid 0 -0.889)
					(end 0 0.889)
				)
			)
			(stroke
				(width 0)
				(type default)
			)
			(fill no)
			(layer "F.CrtYd")
		)
		(pad "1" thru_hole circle
			(at 0 0 90)
			(size 0.508 0.508)
			(drill 0.254)
			(layers "*.Cu" "*.Mask")
			(remove_unused_layers no)
			(net "IO_L20P_35")
			(clearance 0.1016)
			(padstack
				(mode front_inner_back)
				(layer "Inner"
					(shape circle)
					(size 0.508 0.508)
					(clearance 0.1016)
				)
				(layer "B.Cu"
					(shape circle)
					(size 0.762 0.762)
					(clearance -0.0254)
				)
			)
		)
	)
	(footprint ""
		(layer "F.Cu")
		(at 14.732 -37.211 -90)
		(property "Reference" "R365"
			(at 1.27 3.77063 90)
			(unlocked yes)
			(layer "F.SilkS")
			(effects
				(font
					(size 0.7874 0.5842)
					(thickness 0.1524)
				)
			)
		)
		(property "Value" "VAL*"
			(at 0.02032 2.13233 270)
			(unlocked yes)
			(layer "F.Fab")
			(hide yes)
			(effects
				(font
					(size 0.7874 0.5842)
					(thickness 0.1524)
				)
			)
		)
		(property "Tolerance" "TOL*"
			(at 0.044704 3.05435 270)
			(unlocked yes)
			(layer "Cmts.User")
			(hide yes)
			(effects
				(font
					(size 0.7874 0.5842)
					(thickness 0.1524)
				)
			)
		)
		(property "User Part Number" "PARTNUM*"
			(at 0.02032 4.024884 270)
			(unlocked yes)
			(layer "Cmts.User")
			(hide yes)
			(effects
				(font
					(size 0.7874 0.5842)
					(thickness 0.1524)
				)
			)
		)
		(property "Device Type" "RESISTOR-G155-14701-01,4.7KOHMA"
			(at 0.008382 1.210564 270)
			(unlocked yes)
			(layer "F.Fab")
			(hide yes)
			(effects
				(font
					(size 0.7874 0.5842)
					(thickness 0.1524)
				)
			)
		)
		(duplicate_pad_numbers_are_jumpers no)
		(fp_line
			(start -1.143 0.5588)
			(end 1.143 0.5588)
			(stroke
				(width 0.1)
				(type default)
			)
			(layer "F.SilkS")
		)
		(fp_line
			(start 1.143 0.5588)
			(end 1.143 -0.5588)
			(stroke
				(width 0.1)
				(type default)
			)
			(layer "F.SilkS")
		)
		(fp_line
			(start -1.143 -0.5588)
			(end -1.143 0.5588)
			(stroke
				(width 0.1)
				(type default)
			)
			(layer "F.SilkS")
		)
		(fp_line
			(start 1.143 -0.5588)
			(end -1.143 -0.5588)
			(stroke
				(width 0.1)
				(type default)
			)
			(layer "F.SilkS")
		)
		(fp_rect
			(start 1.143 0.5588)
			(end -1.143 -0.5588)
			(stroke
				(width 0)
				(type default)
			)
			(fill no)
			(layer "F.CrtYd")
		)
		(fp_line
			(start -0.508 0.3048)
			(end 0.508 0.3048)
			(stroke
				(width 0.1)
				(type default)
			)
			(layer "F.Fab")
		)
		(fp_line
			(start 0.508 0.3048)
			(end 0.508 -0.3048)
			(stroke
				(width 0.1)
				(type default)
			)
			(layer "F.Fab")
		)
		(fp_line
			(start -0.508 -0.3048)
			(end -0.508 0.3048)
			(stroke
				(width 0.1)
				(type default)
			)
			(layer "F.Fab")
		)
		(fp_line
			(start 0.508 -0.3048)
			(end -0.508 -0.3048)
			(stroke
				(width 0.1)
				(type default)
			)
			(layer "F.Fab")
		)
		(pad "1" smd rect
			(at -0.5334 0 270)
			(size 0.7112 0.6096)
			(layers "F.Cu" "F.Mask" "F.Paste")
			(net "XP3R3V_FPGA")
		)
		(pad "2" smd rect
			(at 0.5334 0 270)
			(size 0.7112 0.6096)
			(layers "F.Cu" "F.Mask" "F.Paste")
			(net "SMA3_SIG_OUT_BF_EN_N")
		)
		(zone
			(layer "F.Cu")
			(hatch none 0.5)
			(connect_pads
				(clearance 0)
			)
			(min_thickness 0.25)
			(keepout
				(tracks not_allowed)
				(vias allowed)
				(pads allowed)
				(copperpour not_allowed)
				(footprints allowed)
			)
			(placement
				(enabled no)
				(sheetname "")
			)
			(fill
				(thermal_gap 0.5)
				(thermal_bridge_width 0.5)
				(island_removal_mode 0)
			)
			(polygon
				(pts
					(xy 14.4272 -37.1348) (xy 15.0368 -37.1348) (xy 15.0368 -37.2872) (xy 14.4272 -37.2872)
				)
			)
		)
		(zone
			(layer "F.Cu")
			(hatch none 0.5)
			(connect_pads
				(clearance 0)
			)
			(min_thickness 0.25)
			(keepout
				(tracks allowed)
				(vias not_allowed)
				(pads allowed)
				(copperpour not_allowed)
				(footprints allowed)
			)
			(placement
				(enabled no)
				(sheetname "")
			)
			(fill
				(thermal_gap 0.5)
				(thermal_bridge_width 0.5)
				(island_removal_mode 0)
			)
			(polygon
				(pts
					(xy 14.4272 -37.1348) (xy 15.0368 -37.1348) (xy 15.0368 -37.2872) (xy 14.4272 -37.2872)
				)
			)
		)
	)
	(footprint ""
		(layer "F.Cu")
		(at 120.269 -89.535 -90)
		(property "Reference" "R114"
			(at 3.429 0.08763 90)
			(unlocked yes)
			(layer "F.SilkS")
			(effects
				(font
					(size 0.7874 0.5842)
					(thickness 0.1524)
				)
			)
		)
		(property "Value" "VAL*"
			(at 0.02032 2.13233 270)
			(unlocked yes)
			(layer "F.Fab")
			(hide yes)
			(effects
				(font
					(size 0.7874 0.5842)
					(thickness 0.1524)
				)
			)
		)
		(property "Device Type" "RESISTOR-G155-14701-01,4.7KOHMA"
			(at 0.008382 1.210564 270)
			(unlocked yes)
			(layer "F.Fab")
			(hide yes)
			(effects
				(font
					(size 0.7874 0.5842)
					(thickness 0.1524)
				)
			)
		)
		(property "User Part Number" "PARTNUM*"
			(at 0.02032 4.024884 270)
			(unlocked yes)
			(layer "Cmts.User")
			(hide yes)
			(effects
				(font
					(size 0.7874 0.5842)
					(thickness 0.1524)
				)
			)
		)
		(property "Tolerance" "TOL*"
			(at 0.044704 3.05435 270)
			(unlocked yes)
			(layer "Cmts.User")
			(hide yes)
			(effects
				(font
					(size 0.7874 0.5842)
					(thickness 0.1524)
				)
			)
		)
		(duplicate_pad_numbers_are_jumpers no)
		(fp_line
			(start -1.143 0.5588)
			(end 1.143 0.5588)
			(stroke
				(width 0.1)
				(type default)
			)
			(layer "F.SilkS")
		)
		(fp_line
			(start 1.143 0.5588)
			(end 1.143 -0.5588)
			(stroke
				(width 0.1)
				(type default)
			)
			(layer "F.SilkS")
		)
		(fp_line
			(start -1.143 -0.5588)
			(end -1.143 0.5588)
			(stroke
				(width 0.1)
				(type default)
			)
			(layer "F.SilkS")
		)
		(fp_line
			(start 1.143 -0.5588)
			(end -1.143 -0.5588)
			(stroke
				(width 0.1)
				(type default)
			)
			(layer "F.SilkS")
		)
		(fp_rect
			(start 1.143 -0.5588)
			(end -1.143 0.5588)
			(stroke
				(width 0)
				(type default)
			)
			(fill no)
			(layer "F.CrtYd")
		)
		(fp_line
			(start -0.508 0.3048)
			(end 0.508 0.3048)
			(stroke
				(width 0.1)
				(type default)
			)
			(layer "F.Fab")
		)
		(fp_line
			(start 0.508 0.3048)
			(end 0.508 -0.3048)
			(stroke
				(width 0.1)
				(type default)
			)
			(layer "F.Fab")
		)
		(fp_line
			(start -0.508 -0.3048)
			(end -0.508 0.3048)
			(stroke
				(width 0.1)
				(type default)
			)
			(layer "F.Fab")
		)
		(fp_line
			(start 0.508 -0.3048)
			(end -0.508 -0.3048)
			(stroke
				(width 0.1)
				(type default)
			)
			(layer "F.Fab")
		)
		(pad "1" smd rect
			(at -0.5334 0 270)
			(size 0.7112 0.6096)
			(layers "F.Cu" "F.Mask" "F.Paste")
			(net "GPS_RST_N")
		)
		(pad "2" smd rect
			(at 0.5334 0 270)
			(size 0.7112 0.6096)
			(layers "F.Cu" "F.Mask" "F.Paste")
			(net "SG")
		)
		(zone
			(layer "F.Cu")
			(hatch none 0.5)
			(connect_pads
				(clearance 0)
			)
			(min_thickness 0.25)
			(keepout
				(tracks allowed)
				(vias not_allowed)
				(pads allowed)
				(copperpour not_allowed)
				(footprints allowed)
			)
			(placement
				(enabled no)
				(sheetname "")
			)
			(fill
				(thermal_gap 0.5)
				(thermal_bridge_width 0.5)
				(island_removal_mode 0)
			)
			(polygon
				(pts
					(xy 120.5738 -89.4588) (xy 120.5738 -89.6112) (xy 119.9642 -89.6112) (xy 119.9642 -89.4588)
				)
			)
		)
	)
)
